FILE_TYPE = CONNECTIVITY;
{Allegro Design Entry HDL 16.6-p007 (v16-6-112F) 10/10/2012}
"PAGE_NUMBER" = 128;
0"NC";
END.
